(kicad_pcb
	(version 20241229)
	(generator "pcbnew")
	(generator_version "9.0")
	(general
		(thickness 1.62)
		(legacy_teardrops no)
	)
	(paper "A3")
	(title_block
		(title "COM Express 7 Baseboard")
		(date "2025-02-04")
		(rev "1.1.2")
		(company "Antmicro Ltd")
		(comment 1 "www.antmicro.com")
		(comment 9 "footprints 443-447 of 802")
	)
	(layers
		(0 "F.Cu" signal)
		(4 "In1.Cu" signal)
		(6 "In2.Cu" signal)
		(8 "In3.Cu" signal)
		(10 "In4.Cu" signal)
		(12 "In5.Cu" signal)
		(14 "In6.Cu" signal)
		(2 "B.Cu" signal)
		(9 "F.Adhes" user "F.Adhesive")
		(11 "B.Adhes" user "B.Adhesive")
		(13 "F.Paste" user)
		(15 "B.Paste" user)
		(5 "F.SilkS" user "F.Silkscreen")
		(7 "B.SilkS" user "B.Silkscreen")
		(1 "F.Mask" user)
		(3 "B.Mask" user)
		(17 "Dwgs.User" user "User.Drawings")
		(19 "Cmts.User" user "User.Comments")
		(21 "Eco1.User" user "User.Eco1")
		(23 "Eco2.User" user "User.Eco2")
		(25 "Edge.Cuts" user)
		(27 "Margin" user)
		(31 "F.CrtYd" user "F.Courtyard")
		(29 "B.CrtYd" user "B.Courtyard")
		(35 "F.Fab" user)
		(33 "B.Fab" user)
	)
	(footprint "antmicro-footprints:TSSOP-8_3x3mm_P0.65mm"
		(layer "F.Cu")
		(at 248.700709 78.085)
		(property "Reference" "U28"
			(at -1.950709 2.735 0)
			(layer "F.SilkS")
			(effects
				(font
					(size 0.7 0.7)
					(thickness 0.15)
				)
				(justify left bottom)
			)
		)
		(property "Value" "NTS0102_TSSOP"
			(at 0 2.8 0)
			(layer "F.Fab")
			(effects
				(font
					(size 0.7 0.7)
					(thickness 0.15)
				)
				(justify left bottom)
			)
		)
		(property "Datasheet" "https://www.mouser.com/datasheet/2/302/NTS0102-1127324.pdf"
			(at 0 0 0)
			(layer "F.Fab")
			(hide yes)
			(effects
				(font
					(size 1.27 1.27)
					(thickness 0.15)
				)
			)
		)
		(property "Author" "Antmicro"
			(at 0 0 0)
			(layer "F.Fab")
			(hide yes)
			(effects
				(font
					(size 1 1)
					(thickness 0.15)
				)
			)
		)
		(property "License" "Apache-2.0"
			(at 0 0 0)
			(layer "F.Fab")
			(hide yes)
			(effects
				(font
					(size 1 1)
					(thickness 0.15)
				)
			)
		)
		(property "MPN" "NTS0102DP"
			(at 0 0 0)
			(layer "F.Fab")
			(hide yes)
			(effects
				(font
					(size 1 1)
					(thickness 0.15)
				)
			)
		)
		(property "Manufacturer" "NXP"
			(at 0 0 0)
			(layer "F.Fab")
			(hide yes)
			(effects
				(font
					(size 1 1)
					(thickness 0.15)
				)
			)
		)
		(sheetname "Misc")
		(sheetfile "misc.kicad_sch")
		(attr smd)
		(fp_line
			(start -1.55 1.561)
			(end 1.552 1.561)
			(stroke
				(width 0.15)
				(type solid)
			)
			(layer "F.SilkS")
		)
		(fp_line
			(start -1.525 -1.537)
			(end 1.552 -1.539)
			(stroke
				(width 0.15)
				(type solid)
			)
			(layer "F.SilkS")
		)
		(fp_circle
			(center -1.87 -1.4)
			(end -1.82 -1.4)
			(stroke
				(width 0.15)
				(type solid)
			)
			(fill yes)
			(layer "F.SilkS")
		)
		(fp_rect
			(start -3.15 -1.789)
			(end 3.15 1.811)
			(stroke
				(width 0.05)
				(type solid)
			)
			(fill no)
			(layer "F.CrtYd")
		)
		(fp_line
			(start -1.55 -0.937)
			(end -1.55 1.561)
			(stroke
				(width 0.15)
				(type solid)
			)
			(layer "F.Fab")
		)
		(fp_line
			(start -1.55 -0.937)
			(end -0.949 -1.539)
			(stroke
				(width 0.15)
				(type solid)
			)
			(layer "F.Fab")
		)
		(fp_line
			(start -1.55 1.561)
			(end 1.552 1.561)
			(stroke
				(width 0.15)
				(type solid)
			)
			(layer "F.Fab")
		)
		(fp_line
			(start -0.949 -1.539)
			(end 1.552 -1.539)
			(stroke
				(width 0.15)
				(type solid)
			)
			(layer "F.Fab")
		)
		(fp_line
			(start 1.552 -1.539)
			(end 1.552 1.561)
			(stroke
				(width 0.15)
				(type solid)
			)
			(layer "F.Fab")
		)
		(pad "1" smd roundrect
			(at -2.148 -0.962)
			(size 1.47 0.4)
			(layers "F.Cu" "F.Mask" "F.Paste")
			(roundrect_rratio 0.25)
			(net 282 "/Misc/PWM_{B5V}")
			(pinfunction "B_{2}")
			(pintype "bidirectional")
			(teardrops
				(best_length_ratio 0.2)
				(max_length 1)
				(best_width_ratio 0.9)
				(max_width 2)
				(curved_edges yes)
				(filter_ratio 0.9)
				(enabled yes)
				(allow_two_segments yes)
				(prefer_zone_connections yes)
			)
		)
		(pad "2" smd roundrect
			(at -2.148 -0.313)
			(size 1.47 0.4)
			(layers "F.Cu" "F.Mask" "F.Paste")
			(roundrect_rratio 0.25)
			(net 1 "GND")
			(pinfunction "GND")
			(pintype "power_in")
			(teardrops
				(best_length_ratio 0.2)
				(max_length 1)
				(best_width_ratio 0.9)
				(max_width 2)
				(curved_edges yes)
				(filter_ratio 0.9)
				(enabled yes)
				(allow_two_segments yes)
				(prefer_zone_connections yes)
			)
		)
		(pad "3" smd roundrect
			(at -2.148 0.338)
			(size 1.47 0.4)
			(layers "F.Cu" "F.Mask" "F.Paste")
			(roundrect_rratio 0.25)
			(net 2 "+3V3")
			(pinfunction "VCC_{A}")
			(pintype "power_in")
			(teardrops
				(best_length_ratio 0.2)
				(max_length 1)
				(best_width_ratio 0.9)
				(max_width 2)
				(curved_edges yes)
				(filter_ratio 0.9)
				(enabled yes)
				(allow_two_segments yes)
				(prefer_zone_connections yes)
			)
		)
		(pad "4" smd roundrect
			(at -2.148 0.987)
			(size 1.47 0.4)
			(layers "F.Cu" "F.Mask" "F.Paste")
			(roundrect_rratio 0.25)
			(net 783 "/Misc/PWM_{B3V3}")
			(pinfunction "A_{2}")
			(pintype "bidirectional")
			(teardrops
				(best_length_ratio 0.2)
				(max_length 1)
				(best_width_ratio 0.9)
				(max_width 2)
				(curved_edges yes)
				(filter_ratio 0.9)
				(enabled yes)
				(allow_two_segments yes)
				(prefer_zone_connections yes)
			)
		)
		(pad "5" smd roundrect
			(at 2.151 0.987)
			(size 1.47 0.4)
			(layers "F.Cu" "F.Mask" "F.Paste")
			(roundrect_rratio 0.25)
			(net 781 "/Misc/TACH_{B3V3}")
			(pinfunction "A_{1}")
			(pintype "bidirectional")
			(teardrops
				(best_length_ratio 0.2)
				(max_length 1)
				(best_width_ratio 0.9)
				(max_width 2)
				(curved_edges yes)
				(filter_ratio 0.9)
				(enabled yes)
				(allow_two_segments yes)
				(prefer_zone_connections yes)
			)
		)
		(pad "6" smd roundrect
			(at 2.151 0.338)
			(size 1.47 0.4)
			(layers "F.Cu" "F.Mask" "F.Paste")
			(roundrect_rratio 0.25)
			(net 2 "+3V3")
			(pinfunction "OE")
			(pintype "input")
			(teardrops
				(best_length_ratio 0.2)
				(max_length 1)
				(best_width_ratio 0.9)
				(max_width 2)
				(curved_edges yes)
				(filter_ratio 0.9)
				(enabled yes)
				(allow_two_segments yes)
				(prefer_zone_connections yes)
			)
		)
		(pad "7" smd roundrect
			(at 2.151 -0.313)
			(size 1.47 0.4)
			(layers "F.Cu" "F.Mask" "F.Paste")
			(roundrect_rratio 0.25)
			(net 52 "+5V")
			(pinfunction "VCC_{B}")
			(pintype "power_in")
			(teardrops
				(best_length_ratio 0.2)
				(max_length 1)
				(best_width_ratio 0.9)
				(max_width 2)
				(curved_edges yes)
				(filter_ratio 0.9)
				(enabled yes)
				(allow_two_segments yes)
				(prefer_zone_connections yes)
			)
		)
		(pad "8" smd roundrect
			(at 2.151 -0.962)
			(size 1.47 0.4)
			(layers "F.Cu" "F.Mask" "F.Paste")
			(roundrect_rratio 0.25)
			(net 281 "/Misc/TACH_{B5V}")
			(pinfunction "B_{1}")
			(pintype "bidirectional")
			(teardrops
				(best_length_ratio 0.2)
				(max_length 1)
				(best_width_ratio 0.9)
				(max_width 2)
				(curved_edges yes)
				(filter_ratio 0.9)
				(enabled yes)
				(allow_two_segments yes)
				(prefer_zone_connections yes)
			)
		)
	)
	(footprint "antmicro-footprints:R_0402_1005Metric"
		(layer "F.Cu")
		(at 155.299 166.36 180)
		(descr "Resistor SMD 0402")
		(tags "resistor SMD 0402")
		(property "Reference" "R65"
			(at -4.551 18.05 0)
			(layer "F.SilkS")
			(effects
				(font
					(size 0.7 0.7)
					(thickness 0.15)
				)
				(justify left bottom)
			)
		)
		(property "Value" "R_220R_0402"
			(at -1.011843 1.772047 0)
			(layer "F.Fab")
			(effects
				(font
					(size 0.7 0.7)
					(thickness 0.15)
				)
				(justify right bottom)
			)
		)
		(property "Datasheet" "https://www.bourns.com/docs/product-datasheets/cr.pdf"
			(at 0 0 180)
			(layer "F.Fab")
			(hide yes)
			(effects
				(font
					(size 1.27 1.27)
					(thickness 0.15)
				)
			)
		)
		(property "Author" "Antmicro"
			(at 310.598 332.72 0)
			(layer "F.Fab")
			(hide yes)
			(effects
				(font
					(size 1 1)
					(thickness 0.15)
				)
			)
		)
		(property "License" "Apache-2.0"
			(at 310.598 332.72 0)
			(layer "F.Fab")
			(hide yes)
			(effects
				(font
					(size 1 1)
					(thickness 0.15)
				)
			)
		)
		(property "MPN" "CR0402-FX-2200GLF"
			(at 310.598 332.72 0)
			(layer "F.Fab")
			(hide yes)
			(effects
				(font
					(size 1 1)
					(thickness 0.15)
				)
			)
		)
		(property "Manufacturer" "Bourns"
			(at 310.598 332.72 0)
			(layer "F.Fab")
			(hide yes)
			(effects
				(font
					(size 1 1)
					(thickness 0.15)
				)
			)
		)
		(property "Public" "False"
			(at 310.598 332.72 0)
			(layer "F.Fab")
			(hide yes)
			(effects
				(font
					(size 1 1)
					(thickness 0.15)
				)
			)
		)
		(property "Tolerance" "1%"
			(at 310.598 332.72 0)
			(layer "F.Fab")
			(hide yes)
			(effects
				(font
					(size 1 1)
					(thickness 0.15)
				)
			)
		)
		(property "Val" "220R"
			(at 310.598 332.72 0)
			(layer "F.Fab")
			(hide yes)
			(effects
				(font
					(size 1 1)
					(thickness 0.15)
				)
			)
		)
		(sheetname "2xSFP+")
		(sheetfile "2xSFP+.kicad_sch")
		(attr smd)
		(fp_rect
			(start -0.925 -0.47)
			(end 0.925 0.47)
			(stroke
				(width 0.05)
				(type default)
			)
			(fill no)
			(layer "F.CrtYd")
		)
		(fp_rect
			(start -0.5 -0.25)
			(end 0.5 0.25)
			(stroke
				(width 0.15)
				(type solid)
			)
			(fill no)
			(layer "F.Fab")
		)
		(pad "1" smd roundrect
			(at -0.48 0 180)
			(size 0.59 0.64)
			(layers "F.Cu" "F.Mask" "F.Paste")
			(roundrect_rratio 0.25)
			(net 931 "/2xSFP+/SFP0_LEDG")
			(pintype "passive")
			(teardrops
				(best_length_ratio 0.2)
				(max_length 1)
				(best_width_ratio 0.9)
				(max_width 2)
				(curved_edges yes)
				(filter_ratio 0.9)
				(enabled yes)
				(allow_two_segments yes)
				(prefer_zone_connections yes)
			)
		)
		(pad "2" smd roundrect
			(at 0.48 0 180)
			(size 0.59 0.64)
			(layers "F.Cu" "F.Mask" "F.Paste")
			(roundrect_rratio 0.25)
			(net 940 "Net-(D8-C)")
			(pintype "passive")
			(teardrops
				(best_length_ratio 0.2)
				(max_length 1)
				(best_width_ratio 0.9)
				(max_width 2)
				(curved_edges yes)
				(filter_ratio 0.9)
				(enabled yes)
				(allow_two_segments yes)
				(prefer_zone_connections yes)
			)
		)
	)
	(footprint "antmicro-footprints:R_0402_1005Metric"
		(layer "F.Cu")
		(at 193.05 130.2 -135)
		(descr "Resistor SMD 0402")
		(tags "resistor SMD 0402")
		(property "Reference" "R225"
			(at -3.65 -0.4 45)
			(layer "F.SilkS")
			(effects
				(font
					(size 0.7 0.7)
					(thickness 0.15)
				)
				(justify right bottom)
			)
		)
		(property "Value" "R_1k_0402"
			(at -1.011843 1.772046 45)
			(layer "F.Fab")
			(effects
				(font
					(size 0.7 0.7)
					(thickness 0.15)
				)
				(justify right bottom)
			)
		)
		(property "Datasheet" "https://www.bourns.com/docs/product-datasheets/cr.pdf"
			(at 0 0 45)
			(layer "F.Fab")
			(hide yes)
			(effects
				(font
					(size 1.27 1.27)
					(thickness 0.15)
				)
			)
		)
		(property "Author" "Antmicro"
			(at 389.100001 263.22 45)
			(layer "F.Fab")
			(hide yes)
			(effects
				(font
					(size 1 1)
					(thickness 0.15)
				)
			)
		)
		(property "License" "Apache-2.0"
			(at 389.100001 263.22 45)
			(layer "F.Fab")
			(hide yes)
			(effects
				(font
					(size 1 1)
					(thickness 0.15)
				)
			)
		)
		(property "MPN" "CR0402-FX-1001GLF"
			(at 389.100001 263.22 45)
			(layer "F.Fab")
			(hide yes)
			(effects
				(font
					(size 1 1)
					(thickness 0.15)
				)
			)
		)
		(property "Manufacturer" "Bourns"
			(at 389.100001 263.22 45)
			(layer "F.Fab")
			(hide yes)
			(effects
				(font
					(size 1 1)
					(thickness 0.15)
				)
			)
		)
		(property "Public" "False"
			(at 389.100001 263.22 45)
			(layer "F.Fab")
			(hide yes)
			(effects
				(font
					(size 1 1)
					(thickness 0.15)
				)
			)
		)
		(property "Tolerance" "1%"
			(at 389.100001 263.22 45)
			(layer "F.Fab")
			(hide yes)
			(effects
				(font
					(size 1 1)
					(thickness 0.15)
				)
			)
		)
		(property "Val" "1k"
			(at 389.100001 263.22 45)
			(layer "F.Fab")
			(hide yes)
			(effects
				(font
					(size 1 1)
					(thickness 0.15)
				)
			)
		)
		(sheetname "PCIe redriver")
		(sheetfile "pcie_redriver.kicad_sch")
		(attr smd)
		(fp_poly
			(pts
				(xy -0.925 -0.47) (xy 0.925 -0.47) (xy 0.925 0.47) (xy -0.925 0.47)
			)
			(stroke
				(width 0.05)
				(type default)
			)
			(fill no)
			(layer "F.CrtYd")
		)
		(fp_poly
			(pts
				(xy -0.5 -0.25) (xy 0.5 -0.25) (xy 0.5 0.25) (xy -0.5 0.25)
			)
			(stroke
				(width 0.15)
				(type solid)
			)
			(fill no)
			(layer "F.Fab")
		)
		(pad "1" smd roundrect
			(at -0.48 0 225)
			(size 0.59 0.64)
			(layers "F.Cu" "F.Mask" "F.Paste")
			(roundrect_rratio 0.25)
			(net 2 "+3V3")
			(pintype "passive")
			(teardrops
				(best_length_ratio 0.2)
				(max_length 1)
				(best_width_ratio 0.9)
				(max_width 2)
				(curved_edges yes)
				(filter_ratio 0.9)
				(enabled yes)
				(allow_two_segments yes)
				(prefer_zone_connections yes)
			)
		)
		(pad "2" smd roundrect
			(at 0.48 0 225)
			(size 0.59 0.64)
			(layers "F.Cu" "F.Mask" "F.Paste")
			(roundrect_rratio 0.25)
			(net 976 "/PCIe redriver/RX_EQ2")
			(pintype "passive")
			(teardrops
				(best_length_ratio 0.2)
				(max_length 1)
				(best_width_ratio 0.9)
				(max_width 2)
				(curved_edges yes)
				(filter_ratio 0.9)
				(enabled yes)
				(allow_two_segments yes)
				(prefer_zone_connections yes)
			)
		)
	)
	(footprint "antmicro-footprints:R_0402_1005Metric"
		(layer "F.Cu")
		(at 136.6 113.11 180)
		(descr "Resistor SMD 0402")
		(tags "resistor SMD 0402")
		(property "Reference" "R14"
			(at -1.15 -1.4 0)
			(layer "F.SilkS")
			(effects
				(font
					(size 0.7 0.7)
					(thickness 0.15)
				)
				(justify right bottom)
			)
		)
		(property "Value" "R_75R_0402"
			(at -1.011843 1.772047 0)
			(layer "F.Fab")
			(effects
				(font
					(size 0.7 0.7)
					(thickness 0.15)
				)
				(justify right bottom)
			)
		)
		(property "Datasheet" "https://www.bourns.com/docs/product-datasheets/cr.pdf"
			(at 0 0 180)
			(layer "F.Fab")
			(hide yes)
			(effects
				(font
					(size 1.27 1.27)
					(thickness 0.15)
				)
			)
		)
		(property "Author" "Antmicro"
			(at 273.2 226.22 0)
			(layer "F.Fab")
			(hide yes)
			(effects
				(font
					(size 1 1)
					(thickness 0.15)
				)
			)
		)
		(property "License" "Apache-2.0"
			(at 273.2 226.22 0)
			(layer "F.Fab")
			(hide yes)
			(effects
				(font
					(size 1 1)
					(thickness 0.15)
				)
			)
		)
		(property "MPN" "CR0402-FX-75R0GLF"
			(at 273.2 226.22 0)
			(layer "F.Fab")
			(hide yes)
			(effects
				(font
					(size 1 1)
					(thickness 0.15)
				)
			)
		)
		(property "Manufacturer" "Bourns"
			(at 273.2 226.22 0)
			(layer "F.Fab")
			(hide yes)
			(effects
				(font
					(size 1 1)
					(thickness 0.15)
				)
			)
		)
		(property "Public" "False"
			(at 273.2 226.22 0)
			(layer "F.Fab")
			(hide yes)
			(effects
				(font
					(size 1 1)
					(thickness 0.15)
				)
			)
		)
		(property "Tolerance" "1%"
			(at 273.2 226.22 0)
			(layer "F.Fab")
			(hide yes)
			(effects
				(font
					(size 1 1)
					(thickness 0.15)
				)
			)
		)
		(property "Val" "75R"
			(at 273.2 226.22 0)
			(layer "F.Fab")
			(hide yes)
			(effects
				(font
					(size 1 1)
					(thickness 0.15)
				)
			)
		)
		(sheetname "2xUSB3.0+RJ45")
		(sheetfile "usb3+rj45.kicad_sch")
		(attr smd)
		(fp_rect
			(start -0.925 -0.47)
			(end 0.925 0.47)
			(stroke
				(width 0.05)
				(type default)
			)
			(fill no)
			(layer "F.CrtYd")
		)
		(fp_rect
			(start -0.5 -0.25)
			(end 0.5 0.25)
			(stroke
				(width 0.15)
				(type solid)
			)
			(fill no)
			(layer "F.Fab")
		)
		(pad "1" smd roundrect
			(at -0.48 0 180)
			(size 0.59 0.64)
			(layers "F.Cu" "F.Mask" "F.Paste")
			(roundrect_rratio 0.25)
			(net 50 "Net-(C12-Pad2)")
			(pintype "passive")
			(teardrops
				(best_length_ratio 0.2)
				(max_length 1)
				(best_width_ratio 0.9)
				(max_width 2)
				(curved_edges yes)
				(filter_ratio 0.9)
				(enabled yes)
				(allow_two_segments yes)
				(prefer_zone_connections yes)
			)
		)
		(pad "2" smd roundrect
			(at 0.48 0 180)
			(size 0.59 0.64)
			(layers "F.Cu" "F.Mask" "F.Paste")
			(roundrect_rratio 0.25)
			(net 549 "Net-(R14-Pad2)")
			(pintype "passive")
			(teardrops
				(best_length_ratio 0.2)
				(max_length 1)
				(best_width_ratio 0.9)
				(max_width 2)
				(curved_edges yes)
				(filter_ratio 0.9)
				(enabled yes)
				(allow_two_segments yes)
				(prefer_zone_connections yes)
			)
		)
	)
	(footprint "antmicro-footprints:R_0402_1005Metric"
		(layer "F.Cu")
		(at 252.665 84.449999 180)
		(descr "Resistor SMD 0402")
		(tags "resistor SMD 0402")
		(property "Reference" "R157"
			(at 0.865 -0.440001 0)
			(layer "F.SilkS")
			(effects
				(font
					(size 0.7 0.7)
					(thickness 0.15)
				)
				(justify right bottom)
			)
		)
		(property "Value" "R_10k_0402"
			(at -1.011843 1.772047 0)
			(layer "F.Fab")
			(effects
				(font
					(size 0.7 0.7)
					(thickness 0.15)
				)
				(justify right bottom)
			)
		)
		(property "Datasheet" "https://www.bourns.com/docs/product-datasheets/cr.pdf"
			(at 0 0 180)
			(layer "F.Fab")
			(hide yes)
			(effects
				(font
					(size 1.27 1.27)
					(thickness 0.15)
				)
			)
		)
		(property "Author" "Antmicro"
			(at 505.33 168.899998 0)
			(layer "F.Fab")
			(hide yes)
			(effects
				(font
					(size 1 1)
					(thickness 0.15)
				)
			)
		)
		(property "License" "Apache-2.0"
			(at 505.33 168.899998 0)
			(layer "F.Fab")
			(hide yes)
			(effects
				(font
					(size 1 1)
					(thickness 0.15)
				)
			)
		)
		(property "MPN" "CR0402-FX-1002GLF"
			(at 505.33 168.899998 0)
			(layer "F.Fab")
			(hide yes)
			(effects
				(font
					(size 1 1)
					(thickness 0.15)
				)
			)
		)
		(property "Manufacturer" "Bourns"
			(at 505.33 168.899998 0)
			(layer "F.Fab")
			(hide yes)
			(effects
				(font
					(size 1 1)
					(thickness 0.15)
				)
			)
		)
		(property "Public" "False"
			(at 505.33 168.899998 0)
			(layer "F.Fab")
			(hide yes)
			(effects
				(font
					(size 1 1)
					(thickness 0.15)
				)
			)
		)
		(property "Tolerance" "1%"
			(at 505.33 168.899998 0)
			(layer "F.Fab")
			(hide yes)
			(effects
				(font
					(size 1 1)
					(thickness 0.15)
				)
			)
		)
		(property "Val" "10k"
			(at 505.33 168.899998 0)
			(layer "F.Fab")
			(hide yes)
			(effects
				(font
					(size 1 1)
					(thickness 0.15)
				)
			)
		)
		(sheetname "Misc")
		(sheetfile "misc.kicad_sch")
		(attr smd)
		(fp_rect
			(start -0.925 -0.47)
			(end 0.925 0.47)
			(stroke
				(width 0.05)
				(type default)
			)
			(fill no)
			(layer "F.CrtYd")
		)
		(fp_rect
			(start -0.5 -0.25)
			(end 0.5 0.25)
			(stroke
				(width 0.15)
				(type solid)
			)
			(fill no)
			(layer "F.Fab")
		)
		(pad "1" smd roundrect
			(at -0.48 0 180)
			(size 0.59 0.64)
			(layers "F.Cu" "F.Mask" "F.Paste")
			(roundrect_rratio 0.25)
			(net 595 "/Misc/PWM_{SRCSEL}")
			(pintype "passive")
			(teardrops
				(best_length_ratio 0.2)
				(max_length 1)
				(best_width_ratio 0.9)
				(max_width 2)
				(curved_edges yes)
				(filter_ratio 0.9)
				(enabled yes)
				(allow_two_segments yes)
				(prefer_zone_connections yes)
			)
		)
		(pad "2" smd roundrect
			(at 0.48 0 180)
			(size 0.59 0.64)
			(layers "F.Cu" "F.Mask" "F.Paste")
			(roundrect_rratio 0.25)
			(net 2 "+3V3")
			(pintype "passive")
			(teardrops
				(best_length_ratio 0.2)
				(max_length 1)
				(best_width_ratio 0.9)
				(max_width 2)
				(curved_edges yes)
				(filter_ratio 0.9)
				(enabled yes)
				(allow_two_segments yes)
				(prefer_zone_connections yes)
			)
		)
	)
)
